FILE_TYPE = CONNECTIVITY;
{Allegro Design Entry HDL 17.4-2019 S026 (4007227) 1/17/2022}
"PAGE_NUMBER" = 130;
0"NC";
1"PVDD18_S5_P0\g";
2"P1V8_AUX\g";
3"GND\g";
4"GND\g";
5"ESPI_CPU0_ALERT_N";
6"ESPI_CPU0_ALERT_P0_N";
7"FM_ESPI_CPU0_ALERT_R_SEL";
8"ESPI_CPU0_ALERT_PLD_N";
9"P1V8_AUX\g";
10"ESPI_CPU0_ALERT_N";
11"ESPI_CPU0_ALERT_PLD_N";
12"ESPI_CPU0_ALERT_R1_N";
%"NC7SB3157P6X"
"1","(-4900,5025)","2","pure_quanta","I1";
;
LOCATION"U8000"
SEC"1"
VALUE"NC7SB3157P6X"
PART_TYPE"SMLF"
MATERIAL"IC"
SEC_TYPE""
CDS_LMAN_SYM_OUTLINE"-150,100,150,-100"
NEEDS_NO_SIZE"TRUE"
CDS_LIB"pure_quanta"
PART_NUMBER"ALSB3157000";
"A"
$PN"4"6;
"VCC"
$PN"5"9;
"S"
$PN"6"7;
"B0"
$PN"3"8;
"GND"
$PN"2"3;
"B1"
$PN"1"12;
%"Q_RES"
"2","(-2750,6050)","0","pure_quanta","I11";
;
LOCATION"R8035"
$SEC"1"
CDS_SEC"1"
TOLERANCE"5%"
VALUE"4.7K"
WATTAGE"1/16W"
MATERIAL"EMPTY"
PACK_TYPE"0402LF"
CDS_LIB"pure_quanta"
PART_NUMBER"CS24702JB10";
"A"
$PN"1"2;
"B"
$PN"2"10;
%"Q_RES"
"2","(-2350,6050)","0","pure_quanta","I12";
;
LOCATION"R8036"
$SEC"1"
CDS_SEC"1"
VALUE"4.7K"
WATTAGE"1/16W"
TOLERANCE"5%"
MATERIAL"EMPTY"
PACK_TYPE"0402LF"
CDS_LIB"pure_quanta"
PART_NUMBER"CS24702JB10";
"A"
$PN"1"1;
"B"
$PN"2"11;
%"UNIVERSAL_POWER"
"1","(-2350,6375)","0","pure_quanta_power","I16";
;
HDL_POWER"PVDD18_S5_P0"
CDS_LIB"pure_quanta_power";
"A"1;
%"UNIVERSAL_POWER"
"1","(-2750,6375)","0","pure_quanta_power","I17";
;
HDL_POWER"P1V8_AUX"
CDS_LIB"pure_quanta_power";
"A"2;
%"GND"
"1","(-4325,5025)","1","pure_quanta_power","I2";
;
SIZE"1B"
CDS_LIB"pure_quanta_power"
HDL_POWER"GND";
"A<SIZE-1..0>\NAC"3;
%"Q_RES"
"1","(-3475,5075)","0","pure_quanta","I23";
;
LOCATION"R8034"
SEC"1"
WATTAGE"1/16W"
MATERIAL"CHIP"
VALUE"0"
PACK_TYPE"0402LF"
TOLERANCE"5%"
SEC_TYPE"0402LF"
CDS_LIB"pure_quanta"
PART_NUMBER"CS00002JB13";
"B"
$PN"2"5;
"A"
$PN"1"12;
%"Q_RES"
"1","(-4950,4650)","0","pure_quanta","I24";
;
LOCATION"R1197"
$SEC"1"
CDS_SEC"1"
WATTAGE"1/16W"
MATERIAL"EMPTY"
TOLERANCE"5%"
VALUE"0"
PACK_TYPE"0402LF"
CDS_LIB"pure_quanta"
PART_NUMBER"CS00002JB13";
"B"
$PN"2"5;
"A"
$PN"1"6;
%"UNIVERSAL_POWER"
"1","(-7325,5850)","0","pure_quanta_power","I3";
;
HDL_POWER"P1V8_AUX"
CDS_LIB"pure_quanta_power";
"A"9;
%"Q_CAP"
"1","(-7325,5500)","2","pure_quanta","I4";
;
LOCATION"C8007"
$SEC"1"
CDS_SEC"1"
MATERIAL"X7R"
PACK_TYPE"0402"
TOLERANCE"10%"
VALUE"0.1UF"
VOLTAGE"25V"
CDS_LIB"pure_quanta"
PART_NUMBER"CH4104K1B00";
"B"
$PN"2"4;
"A"
$PN"1"9;
%"GND"
"1","(-7325,5250)","2","pure_quanta_power","I5";
;
SIZE"1B"
CDS_LIB"pure_quanta_power"
HDL_POWER"GND";
"A<SIZE-1..0>\NAC"4;
END.
